(kicad_pcb
	(version 20260206)
	(generator "pcbnew")
	(generator_version "10.0")
	(general
		(thickness 1.6)
		(legacy_teardrops no)
	)
	(paper "A4")
	(title_block
		(title "03242023_DA0F0TMBIJ0_F0T_Motherboard_J_brd_V01_OCP.brd")
		(comment 1 "Grand Teton / footprints 753-759 of 6105")
	)
	(layers
		(0 "F.Cu" signal "TOP")
		(4 "In1.Cu" signal "GND")
		(6 "In2.Cu" signal "IN1")
		(8 "In3.Cu" signal "GND1")
		(10 "In4.Cu" signal "IN2")
		(12 "In5.Cu" signal "GND2")
		(14 "In6.Cu" signal "IN3")
		(16 "In7.Cu" signal "GND3")
		(18 "In8.Cu" signal "VCC")
		(20 "In9.Cu" signal "VCC1")
		(22 "In10.Cu" signal "GND4")
		(24 "In11.Cu" signal "IN4")
		(26 "In12.Cu" signal "GND5")
		(28 "In13.Cu" signal "IN5")
		(30 "In14.Cu" signal "GND6")
		(32 "In15.Cu" signal "IN6")
		(34 "In16.Cu" signal "GND7")
		(2 "B.Cu" signal "BOTTOM")
		(9 "F.Adhes" user "F.Adhesive")
		(11 "B.Adhes" user "B.Adhesive")
		(13 "F.Paste" user "Package Geometry/Pastemask Top")
		(15 "B.Paste" user "Package Geometry/Pastemask Bottom")
		(5 "F.SilkS" user "Ref Des/Silkscreen Top")
		(7 "B.SilkS" user "Ref Des/Silkscreen Bottom")
		(1 "F.Mask" user "Board Geometry/Soldermask Top")
		(3 "B.Mask" user "Board Geometry/Soldermask Bottom")
		(17 "Dwgs.User" user "User.Drawings")
		(19 "Cmts.User" user "User.Comments")
		(21 "Eco1.User" user "User.Eco1")
		(23 "Eco2.User" user "User.Eco2")
		(25 "Edge.Cuts" user "Board Geometry/Outline")
		(27 "Margin" user)
		(31 "F.CrtYd" user "Package Geometry/Place Bound Top")
		(29 "B.CrtYd" user "Package Geometry/Place Bound Bottom")
		(35 "F.Fab" user "Ref Des/Assembly Top")
		(33 "B.Fab" user "Ref Des/Assembly Bottom")
	)
	(footprint ""
		(layer "F.Cu")
		(at 428.226474 -121.61266 180)
		(property "Reference" "PC628"
			(at 0 0 180)
			(layer "F.SilkS")
			(hide yes)
			(effects
				(font
					(size 1.27 1.27)
				)
			)
		)
		(property "Value" ""
			(at 0 0 180)
			(layer "F.Fab")
			(effects
				(font
					(size 1.27 1.27)
				)
			)
		)
		(duplicate_pad_numbers_are_jumpers no)
		(fp_line
			(start 0.7874 0.4064)
			(end -0.7874 0.4064)
			(stroke
				(width 0.1524)
				(type default)
			)
			(layer "F.SilkS")
		)
		(fp_line
			(start 0.7874 -0.4064)
			(end 0.7874 0.4064)
			(stroke
				(width 0.1524)
				(type default)
			)
			(layer "F.SilkS")
		)
		(fp_line
			(start -0.7874 0.4064)
			(end -0.7874 -0.4064)
			(stroke
				(width 0.1524)
				(type default)
			)
			(layer "F.SilkS")
		)
		(fp_line
			(start -0.7874 -0.4064)
			(end 0.7874 -0.4064)
			(stroke
				(width 0.1524)
				(type default)
			)
			(layer "F.SilkS")
		)
		(fp_line
			(start 0.67945 0.3048)
			(end 0.120396 0.3048)
			(stroke
				(width 0.1)
				(type default)
			)
			(layer "F.Fab")
		)
		(fp_line
			(start 0.67945 -0.3048)
			(end 0.67945 0.3048)
			(stroke
				(width 0.1)
				(type default)
			)
			(layer "F.Fab")
		)
		(fp_line
			(start 0.12065 -0.2794)
			(end 0.12065 -0.3048)
			(stroke
				(width 0.1)
				(type default)
			)
			(layer "F.Fab")
		)
		(fp_line
			(start 0.12065 -0.3048)
			(end 0.67945 -0.3048)
			(stroke
				(width 0.1)
				(type default)
			)
			(layer "F.Fab")
		)
		(fp_line
			(start 0.120396 0.3048)
			(end 0.120396 0.2794)
			(stroke
				(width 0.1)
				(type default)
			)
			(layer "F.Fab")
		)
		(fp_line
			(start 0.120396 0.2794)
			(end -0.12065 0.2794)
			(stroke
				(width 0.1)
				(type default)
			)
			(layer "F.Fab")
		)
		(fp_line
			(start -0.12065 0.3048)
			(end -0.67945 0.3048)
			(stroke
				(width 0.1)
				(type default)
			)
			(layer "F.Fab")
		)
		(fp_line
			(start -0.12065 0.2794)
			(end -0.12065 0.3048)
			(stroke
				(width 0.1)
				(type default)
			)
			(layer "F.Fab")
		)
		(fp_line
			(start -0.12065 -0.2794)
			(end 0.12065 -0.2794)
			(stroke
				(width 0.1)
				(type default)
			)
			(layer "F.Fab")
		)
		(fp_line
			(start -0.12065 -0.305054)
			(end -0.12065 -0.2794)
			(stroke
				(width 0.1)
				(type default)
			)
			(layer "F.Fab")
		)
		(fp_line
			(start -0.67945 0.3048)
			(end -0.67945 -0.305054)
			(stroke
				(width 0.1)
				(type default)
			)
			(layer "F.Fab")
		)
		(fp_line
			(start -0.67945 -0.305054)
			(end -0.12065 -0.305054)
			(stroke
				(width 0.1)
				(type default)
			)
			(layer "F.Fab")
		)
		(pad "1" smd circle
			(at -0.40005 0 180)
			(size 0 0)
			(layers "F.Cu" "F.Mask" "F.Paste")
			(net "PVCCD_HV_CPU0_ISENSE_N")
		)
		(pad "2" smd circle
			(at 0.40005 0 180)
			(size 0 0)
			(layers "F.Cu" "F.Mask" "F.Paste")
			(net "GND")
		)
	)
	(footprint ""
		(layer "F.Cu")
		(at 292.34638 -411.21584)
		(property "Reference" "C2458"
			(at 0 0 0)
			(layer "F.SilkS")
			(hide yes)
			(effects
				(font
					(size 1.27 1.27)
				)
			)
		)
		(property "Value" ""
			(at 0 0 0)
			(layer "F.Fab")
			(effects
				(font
					(size 1.27 1.27)
				)
			)
		)
		(duplicate_pad_numbers_are_jumpers no)
		(fp_line
			(start -0.7874 -0.4064)
			(end 0.7874 -0.4064)
			(stroke
				(width 0.1524)
				(type default)
			)
			(layer "F.SilkS")
		)
		(fp_line
			(start -0.7874 0.4064)
			(end -0.7874 -0.4064)
			(stroke
				(width 0.1524)
				(type default)
			)
			(layer "F.SilkS")
		)
		(fp_line
			(start 0.7874 -0.4064)
			(end 0.7874 0.4064)
			(stroke
				(width 0.1524)
				(type default)
			)
			(layer "F.SilkS")
		)
		(fp_line
			(start 0.7874 0.4064)
			(end -0.7874 0.4064)
			(stroke
				(width 0.1524)
				(type default)
			)
			(layer "F.SilkS")
		)
		(fp_line
			(start -0.67945 -0.305054)
			(end -0.12065 -0.305054)
			(stroke
				(width 0.1)
				(type default)
			)
			(layer "F.Fab")
		)
		(fp_line
			(start -0.67945 0.3048)
			(end -0.67945 -0.305054)
			(stroke
				(width 0.1)
				(type default)
			)
			(layer "F.Fab")
		)
		(fp_line
			(start -0.12065 -0.305054)
			(end -0.12065 -0.2794)
			(stroke
				(width 0.1)
				(type default)
			)
			(layer "F.Fab")
		)
		(fp_line
			(start -0.12065 -0.2794)
			(end 0.12065 -0.2794)
			(stroke
				(width 0.1)
				(type default)
			)
			(layer "F.Fab")
		)
		(fp_line
			(start -0.12065 0.2794)
			(end -0.12065 0.3048)
			(stroke
				(width 0.1)
				(type default)
			)
			(layer "F.Fab")
		)
		(fp_line
			(start -0.12065 0.3048)
			(end -0.67945 0.3048)
			(stroke
				(width 0.1)
				(type default)
			)
			(layer "F.Fab")
		)
		(fp_line
			(start 0.120396 0.2794)
			(end -0.12065 0.2794)
			(stroke
				(width 0.1)
				(type default)
			)
			(layer "F.Fab")
		)
		(fp_line
			(start 0.120396 0.3048)
			(end 0.120396 0.2794)
			(stroke
				(width 0.1)
				(type default)
			)
			(layer "F.Fab")
		)
		(fp_line
			(start 0.12065 -0.3048)
			(end 0.67945 -0.3048)
			(stroke
				(width 0.1)
				(type default)
			)
			(layer "F.Fab")
		)
		(fp_line
			(start 0.12065 -0.2794)
			(end 0.12065 -0.3048)
			(stroke
				(width 0.1)
				(type default)
			)
			(layer "F.Fab")
		)
		(fp_line
			(start 0.67945 -0.3048)
			(end 0.67945 0.3048)
			(stroke
				(width 0.1)
				(type default)
			)
			(layer "F.Fab")
		)
		(fp_line
			(start 0.67945 0.3048)
			(end 0.120396 0.3048)
			(stroke
				(width 0.1)
				(type default)
			)
			(layer "F.Fab")
		)
		(pad "1" smd circle
			(at -0.40005 0)
			(size 0 0)
			(layers "F.Cu" "F.Mask" "F.Paste")
			(net "P3V3_AUX")
		)
		(pad "2" smd circle
			(at 0.40005 0)
			(size 0 0)
			(layers "F.Cu" "F.Mask" "F.Paste")
			(net "GND")
		)
	)
	(footprint ""
		(layer "F.Cu")
		(at 43.60037 -363.251242)
		(property "Reference" "PL43"
			(at 0.233172 -3.211068 0)
			(unlocked yes)
			(layer "F.SilkS")
			(effects
				(font
					(size 0.7874 0.5842)
					(thickness 0.1524)
				)
				(justify left)
			)
		)
		(property "Value" ""
			(at 0 0 0)
			(layer "F.Fab")
			(effects
				(font
					(size 1.27 1.27)
				)
			)
		)
		(duplicate_pad_numbers_are_jumpers no)
		(fp_line
			(start -2.249932 -2.249932)
			(end 2.249932 -2.249932)
			(stroke
				(width 0.1524)
				(type default)
			)
			(layer "F.SilkS")
		)
		(fp_line
			(start -2.249932 -1.3843)
			(end -2.249932 -2.249932)
			(stroke
				(width 0.1524)
				(type default)
			)
			(layer "F.SilkS")
		)
		(fp_line
			(start -2.249932 2.249932)
			(end -2.249932 1.3843)
			(stroke
				(width 0.1524)
				(type default)
			)
			(layer "F.SilkS")
		)
		(fp_line
			(start 2.249932 -2.249932)
			(end 2.249932 -1.3843)
			(stroke
				(width 0.1524)
				(type default)
			)
			(layer "F.SilkS")
		)
		(fp_line
			(start 2.249932 1.3843)
			(end 2.249932 2.249932)
			(stroke
				(width 0.1524)
				(type default)
			)
			(layer "F.SilkS")
		)
		(fp_line
			(start 2.249932 2.249932)
			(end -2.249932 2.249932)
			(stroke
				(width 0.1524)
				(type default)
			)
			(layer "F.SilkS")
		)
		(fp_line
			(start -2.249932 -2.249932)
			(end 2.249932 -2.249932)
			(stroke
				(width 0.1)
				(type default)
			)
			(layer "F.Fab")
		)
		(fp_line
			(start -2.249932 2.249932)
			(end -2.249932 -2.249932)
			(stroke
				(width 0.1)
				(type default)
			)
			(layer "F.Fab")
		)
		(fp_line
			(start 2.249932 -2.249932)
			(end 2.249932 2.249932)
			(stroke
				(width 0.1)
				(type default)
			)
			(layer "F.Fab")
		)
		(fp_line
			(start 2.249932 2.249932)
			(end -2.249932 2.249932)
			(stroke
				(width 0.1)
				(type default)
			)
			(layer "F.Fab")
		)
		(pad "1" smd rect
			(at -1.82499 0)
			(size 1.0668 2.5146)
			(layers "F.Cu" "F.Mask" "F.Paste")
			(net "P12V_AUX")
		)
		(pad "2" smd rect
			(at 1.82499 0)
			(size 1.0668 2.5146)
			(layers "F.Cu" "F.Mask" "F.Paste")
			(net "SW_P12V_PVCCFA_EHV_FIVRA_CPU1_L")
		)
	)
	(footprint ""
		(layer "F.Cu")
		(at 202.59294 -132.050028)
		(property "Reference" "Q54"
			(at -1.651 -2.25933 0)
			(unlocked yes)
			(layer "F.SilkS")
			(effects
				(font
					(size 0.7874 0.5842)
					(thickness 0.1524)
				)
				(justify left)
			)
		)
		(property "Value" ""
			(at 0 0 0)
			(layer "F.Fab")
			(effects
				(font
					(size 1.27 1.27)
				)
			)
		)
		(duplicate_pad_numbers_are_jumpers no)
		(fp_line
			(start -1.603248 -1.500124)
			(end 1.603248 -1.500124)
			(stroke
				(width 0.1524)
				(type default)
			)
			(layer "F.SilkS")
		)
		(fp_line
			(start -1.603248 1.500124)
			(end -1.603248 -1.500124)
			(stroke
				(width 0.1524)
				(type default)
			)
			(layer "F.SilkS")
		)
		(fp_line
			(start 1.603248 -1.500124)
			(end 1.603248 1.500124)
			(stroke
				(width 0.1524)
				(type default)
			)
			(layer "F.SilkS")
		)
		(fp_line
			(start 1.603248 1.500124)
			(end -1.603248 1.500124)
			(stroke
				(width 0.1524)
				(type default)
			)
			(layer "F.SilkS")
		)
		(fp_line
			(start -1.249934 -1.169924)
			(end -1.249934 -0.729996)
			(stroke
				(width 0.1)
				(type default)
			)
			(layer "F.Fab")
		)
		(fp_line
			(start -1.249934 -0.729996)
			(end -0.6985 -0.729996)
			(stroke
				(width 0.1)
				(type default)
			)
			(layer "F.Fab")
		)
		(fp_line
			(start -1.249934 0.729996)
			(end -1.249934 1.169924)
			(stroke
				(width 0.1)
				(type default)
			)
			(layer "F.Fab")
		)
		(fp_line
			(start -1.249934 1.169924)
			(end -0.700024 1.169924)
			(stroke
				(width 0.1)
				(type default)
			)
			(layer "F.Fab")
		)
		(fp_line
			(start -0.700024 -1.500124)
			(end -0.700024 -1.169924)
			(stroke
				(width 0.1)
				(type default)
			)
			(layer "F.Fab")
		)
		(fp_line
			(start -0.700024 -1.169924)
			(end -1.249934 -1.169924)
			(stroke
				(width 0.1)
				(type default)
			)
			(layer "F.Fab")
		)
		(fp_line
			(start -0.700024 1.169924)
			(end -0.700024 1.500124)
			(stroke
				(width 0.1)
				(type default)
			)
			(layer "F.Fab")
		)
		(fp_line
			(start -0.700024 1.500124)
			(end 0.700024 1.500124)
			(stroke
				(width 0.1)
				(type default)
			)
			(layer "F.Fab")
		)
		(fp_line
			(start -0.6985 -0.729996)
			(end -0.6985 0.729996)
			(stroke
				(width 0.1)
				(type default)
			)
			(layer "F.Fab")
		)
		(fp_line
			(start -0.6985 0.729996)
			(end -1.249934 0.729996)
			(stroke
				(width 0.1)
				(type default)
			)
			(layer "F.Fab")
		)
		(fp_line
			(start 0.700024 -1.500124)
			(end -0.700024 -1.500124)
			(stroke
				(width 0.1)
				(type default)
			)
			(layer "F.Fab")
		)
		(fp_line
			(start 0.700024 -0.219964)
			(end 0.700024 -1.500124)
			(stroke
				(width 0.1)
				(type default)
			)
			(layer "F.Fab")
		)
		(fp_line
			(start 0.700024 0.219964)
			(end 1.249934 0.219964)
			(stroke
				(width 0.1)
				(type default)
			)
			(layer "F.Fab")
		)
		(fp_line
			(start 0.700024 1.500124)
			(end 0.700024 0.219964)
			(stroke
				(width 0.1)
				(type default)
			)
			(layer "F.Fab")
		)
		(fp_line
			(start 1.249934 -0.219964)
			(end 0.700024 -0.219964)
			(stroke
				(width 0.1)
				(type default)
			)
			(layer "F.Fab")
		)
		(fp_line
			(start 1.249934 0.219964)
			(end 1.249934 -0.219964)
			(stroke
				(width 0.1)
				(type default)
			)
			(layer "F.Fab")
		)
		(fp_rect
			(start -0.700024 1.500124)
			(end 0.700024 -1.500124)
			(stroke
				(width 0)
				(type default)
			)
			(fill no)
			(layer "F.Fab")
		)
		(pad "D" smd rect
			(at 0.999998 0 270)
			(size 0.8128 0.9144)
			(layers "F.Cu" "F.Mask" "F.Paste")
			(net "P12V_AUX_BLEEDING")
		)
		(pad "G" smd rect
			(at -0.999998 -0.94996 270)
			(size 0.8128 0.9144)
			(layers "F.Cu" "F.Mask" "F.Paste")
			(net "FM_P12V_HSC_EN_R_N")
		)
		(pad "S" smd rect
			(at -0.999998 0.94996 270)
			(size 0.8128 0.9144)
			(layers "F.Cu" "F.Mask" "F.Paste")
			(net "GND")
		)
	)
	(footprint ""
		(layer "F.Cu")
		(at 188.839348 -423.86123 -90)
		(property "Reference" "R2585"
			(at 0 0 270)
			(layer "F.SilkS")
			(hide yes)
			(effects
				(font
					(size 1.27 1.27)
				)
			)
		)
		(property "Value" ""
			(at 0 0 270)
			(layer "F.Fab")
			(effects
				(font
					(size 1.27 1.27)
				)
			)
		)
		(duplicate_pad_numbers_are_jumpers no)
		(fp_line
			(start -0.7874 0.4064)
			(end -0.7874 -0.4064)
			(stroke
				(width 0.1524)
				(type default)
			)
			(layer "F.SilkS")
		)
		(fp_line
			(start 0.7874 0.4064)
			(end -0.7874 0.4064)
			(stroke
				(width 0.1524)
				(type default)
			)
			(layer "F.SilkS")
		)
		(fp_line
			(start -0.7874 -0.4064)
			(end 0.7874 -0.4064)
			(stroke
				(width 0.1524)
				(type default)
			)
			(layer "F.SilkS")
		)
		(fp_line
			(start 0.7874 -0.4064)
			(end 0.7874 0.4064)
			(stroke
				(width 0.1524)
				(type default)
			)
			(layer "F.SilkS")
		)
		(fp_line
			(start -0.67945 0.3048)
			(end -0.67945 -0.305054)
			(stroke
				(width 0.1)
				(type default)
			)
			(layer "F.Fab")
		)
		(fp_line
			(start -0.12065 0.3048)
			(end -0.67945 0.3048)
			(stroke
				(width 0.1)
				(type default)
			)
			(layer "F.Fab")
		)
		(fp_line
			(start 0.120396 0.3048)
			(end 0.120396 0.2794)
			(stroke
				(width 0.1)
				(type default)
			)
			(layer "F.Fab")
		)
		(fp_line
			(start 0.67945 0.3048)
			(end 0.120396 0.3048)
			(stroke
				(width 0.1)
				(type default)
			)
			(layer "F.Fab")
		)
		(fp_line
			(start -0.12065 0.2794)
			(end -0.12065 0.3048)
			(stroke
				(width 0.1)
				(type default)
			)
			(layer "F.Fab")
		)
		(fp_line
			(start 0.120396 0.2794)
			(end -0.12065 0.2794)
			(stroke
				(width 0.1)
				(type default)
			)
			(layer "F.Fab")
		)
		(fp_line
			(start -0.12065 -0.2794)
			(end 0.12065 -0.2794)
			(stroke
				(width 0.1)
				(type default)
			)
			(layer "F.Fab")
		)
		(fp_line
			(start 0.12065 -0.2794)
			(end 0.12065 -0.3048)
			(stroke
				(width 0.1)
				(type default)
			)
			(layer "F.Fab")
		)
		(fp_line
			(start 0.12065 -0.3048)
			(end 0.67945 -0.3048)
			(stroke
				(width 0.1)
				(type default)
			)
			(layer "F.Fab")
		)
		(fp_line
			(start 0.67945 -0.3048)
			(end 0.67945 0.3048)
			(stroke
				(width 0.1)
				(type default)
			)
			(layer "F.Fab")
		)
		(fp_line
			(start -0.67945 -0.305054)
			(end -0.12065 -0.305054)
			(stroke
				(width 0.1)
				(type default)
			)
			(layer "F.Fab")
		)
		(fp_line
			(start -0.12065 -0.305054)
			(end -0.12065 -0.2794)
			(stroke
				(width 0.1)
				(type default)
			)
			(layer "F.Fab")
		)
		(pad "1" smd circle
			(at -0.40005 0 270)
			(size 0 0)
			(layers "F.Cu" "F.Mask" "F.Paste")
			(net "HSC_EN")
		)
		(pad "2" smd circle
			(at 0.40005 0 270)
			(size 0 0)
			(layers "F.Cu" "F.Mask" "F.Paste")
			(net "GND")
		)
	)
	(footprint ""
		(layer "F.Cu")
		(at 83.910678 -408.517344 -90)
		(property "Reference" "C686"
			(at 0 0 270)
			(layer "F.SilkS")
			(hide yes)
			(effects
				(font
					(size 1.27 1.27)
				)
			)
		)
		(property "Value" ""
			(at 0 0 270)
			(layer "F.Fab")
			(effects
				(font
					(size 1.27 1.27)
				)
			)
		)
		(duplicate_pad_numbers_are_jumpers no)
		(fp_line
			(start -0.299974 0.150114)
			(end -0.299974 -0.150114)
			(stroke
				(width 0.1)
				(type default)
			)
			(layer "F.Fab")
		)
		(fp_line
			(start 0.299974 0.150114)
			(end -0.299974 0.150114)
			(stroke
				(width 0.1)
				(type default)
			)
			(layer "F.Fab")
		)
		(fp_line
			(start -0.299974 -0.150114)
			(end 0.299974 -0.150114)
			(stroke
				(width 0.1)
				(type default)
			)
			(layer "F.Fab")
		)
		(fp_line
			(start 0.299974 -0.150114)
			(end 0.299974 0.150114)
			(stroke
				(width 0.1)
				(type default)
			)
			(layer "F.Fab")
		)
		(pad "1" smd rect
			(at -0.2667 0 270)
			(size 0.3048 0.381)
			(layers "F.Cu" "F.Mask" "F.Paste")
			(net "P5E_CPU1_PE4_TX_C_DN<11>")
		)
		(pad "2" smd rect
			(at 0.2667 0 270)
			(size 0.3048 0.381)
			(layers "F.Cu" "F.Mask" "F.Paste")
			(net "P5E_CPU1_PE4_TX_DN<11>")
		)
	)
	(footprint ""
		(layer "F.Cu")
		(at 336.86496 -206.024734)
		(property "Reference" "H23"
			(at -1.58496 4.537456 0)
			(unlocked yes)
			(layer "F.SilkS")
			(effects
				(font
					(size 0.7874 0.5842)
					(thickness 0.1524)
				)
				(justify left)
			)
		)
		(property "Value" ""
			(at 0 0 0)
			(layer "F.Fab")
			(effects
				(font
					(size 1.27 1.27)
				)
			)
		)
		(duplicate_pad_numbers_are_jumpers no)
		(fp_circle
			(center 0 0)
			(end 2.5273 0)
			(stroke
				(width 0.1524)
				(type default)
			)
			(fill no)
			(layer "F.SilkS")
		)
		(fp_circle
			(center 0 0)
			(end 2.5273 0)
			(stroke
				(width 0.1524)
				(type default)
			)
			(fill no)
			(layer "B.SilkS")
		)
		(fp_circle
			(center 0 0)
			(end 2.5273 0)
			(stroke
				(width 0.1)
				(type default)
			)
			(fill no)
			(layer "B.Fab")
		)
		(fp_circle
			(center 0 0)
			(end 2.5273 0)
			(stroke
				(width 0.1)
				(type default)
			)
			(fill no)
			(layer "F.Fab")
		)
		(pad "" np_thru_hole circle
			(at 0 0)
			(size 3.429 3.429)
			(drill 3.429)
			(layers "*.Cu" "*.Mask")
			(clearance 0.381)
			(thermal_gap 0.381)
		)
	)
)
